# S9S_MB_2U (Grand Teton) — schematic netlist excerpt (pin names and nets, part order shuffled) for the footprints in the layout excerpt that follows; sources: Cadence DE-HDL packaged netlist, KiCad conversion of 03242023_DA0F0TMBIJ0_F0T_Motherboard_J_brd_V01_OCP.brd

R1476  Q_RES  1K 1% CHIP  pkg 0402LF  page 200 : A = FM_PCH_RING_OSC_BYPASS_MGPIO_TE ; B = GND
PC452_P1_1  Q_CAP  100NF 50V 10% X7R  pkg C0402  page 293 : A = PVCCINFAON_CPU1 ; B = GND

(kicad_pcb
	(version 20260206)
	(generator "pcbnew")
	(generator_version "10.0")
	(general
		(thickness 1.6)
		(legacy_teardrops no)
	)
	(paper "A4")
	(title_block
		(title "03242023_DA0F0TMBIJ0_F0T_Motherboard_J_brd_V01_OCP.brd")
		(comment 1 "Grand Teton / footprints 650-651 of 6105")
	)
	(layers
		(0 "F.Cu" signal "TOP")
		(4 "In1.Cu" signal "GND")
		(6 "In2.Cu" signal "IN1")
		(8 "In3.Cu" signal "GND1")
		(10 "In4.Cu" signal "IN2")
		(12 "In5.Cu" signal "GND2")
		(14 "In6.Cu" signal "IN3")
		(16 "In7.Cu" signal "GND3")
		(18 "In8.Cu" signal "VCC")
		(20 "In9.Cu" signal "VCC1")
		(22 "In10.Cu" signal "GND4")
		(24 "In11.Cu" signal "IN4")
		(26 "In12.Cu" signal "GND5")
		(28 "In13.Cu" signal "IN5")
		(30 "In14.Cu" signal "GND6")
		(32 "In15.Cu" signal "IN6")
		(34 "In16.Cu" signal "GND7")
		(2 "B.Cu" signal "BOTTOM")
		(9 "F.Adhes" user "F.Adhesive")
		(11 "B.Adhes" user "B.Adhesive")
		(13 "F.Paste" user "Package Geometry/Pastemask Top")
		(15 "B.Paste" user "Package Geometry/Pastemask Bottom")
		(5 "F.SilkS" user "Ref Des/Silkscreen Top")
		(7 "B.SilkS" user "Ref Des/Silkscreen Bottom")
		(1 "F.Mask" user "Board Geometry/Soldermask Top")
		(3 "B.Mask" user "Board Geometry/Soldermask Bottom")
		(17 "Dwgs.User" user "User.Drawings")
		(19 "Cmts.User" user "User.Comments")
		(21 "Eco1.User" user "User.Eco1")
		(23 "Eco2.User" user "User.Eco2")
		(25 "Edge.Cuts" user "Board Geometry/Outline")
		(27 "Margin" user)
		(31 "F.CrtYd" user "Package Geometry/Place Bound Top")
		(29 "B.CrtYd" user "Package Geometry/Place Bound Bottom")
		(35 "F.Fab" user "Ref Des/Assembly Top")
		(33 "B.Fab" user "Ref Des/Assembly Bottom")
	)
	(footprint ""
		(layer "F.Cu")
		(at 62.994032 -143.757904 180)
		(property "Reference" "PC452_P1_1"
			(at 0 0 180)
			(layer "F.SilkS")
			(hide yes)
			(effects
				(font
					(size 1.27 1.27)
				)
			)
		)
		(property "Value" ""
			(at 0 0 180)
			(layer "F.Fab")
			(effects
				(font
					(size 1.27 1.27)
				)
			)
		)
		(duplicate_pad_numbers_are_jumpers no)
		(fp_line
			(start 0.7874 0.4064)
			(end -0.7874 0.4064)
			(stroke
				(width 0.1524)
				(type default)
			)
			(layer "F.SilkS")
		)
		(fp_line
			(start 0.7874 -0.4064)
			(end 0.7874 0.4064)
			(stroke
				(width 0.1524)
				(type default)
			)
			(layer "F.SilkS")
		)
		(fp_line
			(start -0.7874 0.4064)
			(end -0.7874 -0.4064)
			(stroke
				(width 0.1524)
				(type default)
			)
			(layer "F.SilkS")
		)
		(fp_line
			(start -0.7874 -0.4064)
			(end 0.7874 -0.4064)
			(stroke
				(width 0.1524)
				(type default)
			)
			(layer "F.SilkS")
		)
		(fp_line
			(start 0.67945 0.3048)
			(end 0.120396 0.3048)
			(stroke
				(width 0.1)
				(type default)
			)
			(layer "F.Fab")
		)
		(fp_line
			(start 0.67945 -0.3048)
			(end 0.67945 0.3048)
			(stroke
				(width 0.1)
				(type default)
			)
			(layer "F.Fab")
		)
		(fp_line
			(start 0.12065 -0.2794)
			(end 0.12065 -0.3048)
			(stroke
				(width 0.1)
				(type default)
			)
			(layer "F.Fab")
		)
		(fp_line
			(start 0.12065 -0.3048)
			(end 0.67945 -0.3048)
			(stroke
				(width 0.1)
				(type default)
			)
			(layer "F.Fab")
		)
		(fp_line
			(start 0.120396 0.3048)
			(end 0.120396 0.2794)
			(stroke
				(width 0.1)
				(type default)
			)
			(layer "F.Fab")
		)
		(fp_line
			(start 0.120396 0.2794)
			(end -0.12065 0.2794)
			(stroke
				(width 0.1)
				(type default)
			)
			(layer "F.Fab")
		)
		(fp_line
			(start -0.12065 0.3048)
			(end -0.67945 0.3048)
			(stroke
				(width 0.1)
				(type default)
			)
			(layer "F.Fab")
		)
		(fp_line
			(start -0.12065 0.2794)
			(end -0.12065 0.3048)
			(stroke
				(width 0.1)
				(type default)
			)
			(layer "F.Fab")
		)
		(fp_line
			(start -0.12065 -0.2794)
			(end 0.12065 -0.2794)
			(stroke
				(width 0.1)
				(type default)
			)
			(layer "F.Fab")
		)
		(fp_line
			(start -0.12065 -0.305054)
			(end -0.12065 -0.2794)
			(stroke
				(width 0.1)
				(type default)
			)
			(layer "F.Fab")
		)
		(fp_line
			(start -0.67945 0.3048)
			(end -0.67945 -0.305054)
			(stroke
				(width 0.1)
				(type default)
			)
			(layer "F.Fab")
		)
		(fp_line
			(start -0.67945 -0.305054)
			(end -0.12065 -0.305054)
			(stroke
				(width 0.1)
				(type default)
			)
			(layer "F.Fab")
		)
		(pad "1" smd circle
			(at -0.40005 0 180)
			(size 0 0)
			(layers "F.Cu" "F.Mask" "F.Paste")
			(net "PVCCINFAON_CPU1")
		)
		(pad "2" smd circle
			(at 0.40005 0 180)
			(size 0 0)
			(layers "F.Cu" "F.Mask" "F.Paste")
			(net "GND")
		)
	)
	(footprint ""
		(layer "F.Cu")
		(at 317.396622 -61.331348 180)
		(property "Reference" "R1476"
			(at 0 0 180)
			(layer "F.SilkS")
			(hide yes)
			(effects
				(font
					(size 1.27 1.27)
				)
			)
		)
		(property "Value" ""
			(at 0 0 180)
			(layer "F.Fab")
			(effects
				(font
					(size 1.27 1.27)
				)
			)
		)
		(duplicate_pad_numbers_are_jumpers no)
		(fp_line
			(start 0.7874 0.4064)
			(end -0.7874 0.4064)
			(stroke
				(width 0.1524)
				(type default)
			)
			(layer "F.SilkS")
		)
		(fp_line
			(start 0.7874 -0.4064)
			(end 0.7874 0.4064)
			(stroke
				(width 0.1524)
				(type default)
			)
			(layer "F.SilkS")
		)
		(fp_line
			(start -0.7874 0.4064)
			(end -0.7874 -0.4064)
			(stroke
				(width 0.1524)
				(type default)
			)
			(layer "F.SilkS")
		)
		(fp_line
			(start -0.7874 -0.4064)
			(end 0.7874 -0.4064)
			(stroke
				(width 0.1524)
				(type default)
			)
			(layer "F.SilkS")
		)
		(fp_line
			(start 0.67945 0.3048)
			(end 0.120396 0.3048)
			(stroke
				(width 0.1)
				(type default)
			)
			(layer "F.Fab")
		)
		(fp_line
			(start 0.67945 -0.3048)
			(end 0.67945 0.3048)
			(stroke
				(width 0.1)
				(type default)
			)
			(layer "F.Fab")
		)
		(fp_line
			(start 0.12065 -0.2794)
			(end 0.12065 -0.3048)
			(stroke
				(width 0.1)
				(type default)
			)
			(layer "F.Fab")
		)
		(fp_line
			(start 0.12065 -0.3048)
			(end 0.67945 -0.3048)
			(stroke
				(width 0.1)
				(type default)
			)
			(layer "F.Fab")
		)
		(fp_line
			(start 0.120396 0.3048)
			(end 0.120396 0.2794)
			(stroke
				(width 0.1)
				(type default)
			)
			(layer "F.Fab")
		)
		(fp_line
			(start 0.120396 0.2794)
			(end -0.12065 0.2794)
			(stroke
				(width 0.1)
				(type default)
			)
			(layer "F.Fab")
		)
		(fp_line
			(start -0.12065 0.3048)
			(end -0.67945 0.3048)
			(stroke
				(width 0.1)
				(type default)
			)
			(layer "F.Fab")
		)
		(fp_line
			(start -0.12065 0.2794)
			(end -0.12065 0.3048)
			(stroke
				(width 0.1)
				(type default)
			)
			(layer "F.Fab")
		)
		(fp_line
			(start -0.12065 -0.2794)
			(end 0.12065 -0.2794)
			(stroke
				(width 0.1)
				(type default)
			)
			(layer "F.Fab")
		)
		(fp_line
			(start -0.12065 -0.305054)
			(end -0.12065 -0.2794)
			(stroke
				(width 0.1)
				(type default)
			)
			(layer "F.Fab")
		)
		(fp_line
			(start -0.67945 0.3048)
			(end -0.67945 -0.305054)
			(stroke
				(width 0.1)
				(type default)
			)
			(layer "F.Fab")
		)
		(fp_line
			(start -0.67945 -0.305054)
			(end -0.12065 -0.305054)
			(stroke
				(width 0.1)
				(type default)
			)
			(layer "F.Fab")
		)
		(pad "1" smd circle
			(at -0.40005 0 180)
			(size 0 0)
			(layers "F.Cu" "F.Mask" "F.Paste")
			(net "FM_PCH_RING_OSC_BYPASS_MGPIO_TE")
		)
		(pad "2" smd circle
			(at 0.40005 0 180)
			(size 0 0)
			(layers "F.Cu" "F.Mask" "F.Paste")
			(net "GND")
		)
	)
)
